# T6G (Grand Teton) — schematic netlist excerpt (pin names and nets, part order shuffled) for the footprints in the layout excerpt that follows; sources: Cadence DE-HDL packaged netlist, KiCad conversion of 04192023_DAF0TMB3IC0_F0TG_MB_C_brd_V02_OCP.brd

PC12  Q_CAP  0.1UF 25V 10% X7R  pkg 0402  page 193 : A = PVDDCR_CPU0_P0_VCC ; B = GND
R889  Q_RES  10K 5% EMPTY  pkg 0402LF  page 151 : A = SCM_SPARE_0 ; B = GND

(kicad_pcb
	(version 20260206)
	(generator "pcbnew")
	(generator_version "10.0")
	(general
		(thickness 1.6)
		(legacy_teardrops no)
	)
	(paper "A4")
	(title_block
		(title "04192023_DAF0TMB3IC0_F0TG_MB_C_brd_V02_OCP.brd")
		(comment 1 "Grand Teton / footprints 6624-6625 of 8354")
	)
	(layers
		(0 "F.Cu" signal "TOP")
		(4 "In1.Cu" signal "GND")
		(6 "In2.Cu" signal "IN1")
		(8 "In3.Cu" signal "GND1")
		(10 "In4.Cu" signal "IN2")
		(12 "In5.Cu" signal "GND2")
		(14 "In6.Cu" signal "IN3")
		(16 "In7.Cu" signal "GND3")
		(18 "In8.Cu" signal "VCC")
		(20 "In9.Cu" signal "VCC1")
		(22 "In10.Cu" signal "GND4")
		(24 "In11.Cu" signal "IN4")
		(26 "In12.Cu" signal "GND5")
		(28 "In13.Cu" signal "IN5")
		(30 "In14.Cu" signal "GND6")
		(32 "In15.Cu" signal "IN6")
		(34 "In16.Cu" signal "GND7")
		(2 "B.Cu" signal "BOTTOM")
		(9 "F.Adhes" user "F.Adhesive")
		(11 "B.Adhes" user "B.Adhesive")
		(13 "F.Paste" user "Package Geometry/Pastemask Top")
		(15 "B.Paste" user "Package Geometry/Pastemask Bottom")
		(5 "F.SilkS" user "Ref Des/Silkscreen Top")
		(7 "B.SilkS" user "Ref Des/Silkscreen Bottom")
		(1 "F.Mask" user "Board Geometry/Soldermask Top")
		(3 "B.Mask" user "Board Geometry/Soldermask Bottom")
		(17 "Dwgs.User" user "User.Drawings")
		(19 "Cmts.User" user "User.Comments")
		(21 "Eco1.User" user "User.Eco1")
		(23 "Eco2.User" user "User.Eco2")
		(25 "Edge.Cuts" user "Board Geometry/Outline")
		(27 "Margin" user)
		(31 "F.CrtYd" user "Package Geometry/Place Bound Top")
		(29 "B.CrtYd" user "Package Geometry/Place Bound Bottom")
		(35 "F.Fab" user "Ref Des/Assembly Top")
		(33 "B.Fab" user "Ref Des/Assembly Bottom")
	)
	(footprint ""
		(layer "B.Cu")
		(at 383.224278 -137.535158 90)
		(property "Reference" "PC12"
			(at 0 0 90)
			(layer "B.SilkS")
			(hide yes)
			(effects
				(font
					(size 1.27 1.27)
				)
				(justify mirror)
			)
		)
		(property "Value" ""
			(at 0 0 90)
			(layer "B.Fab")
			(effects
				(font
					(size 1.27 1.27)
				)
				(justify mirror)
			)
		)
		(duplicate_pad_numbers_are_jumpers no)
		(fp_line
			(start 0.7874 -0.4064)
			(end -0.7874 -0.4064)
			(stroke
				(width 0.1524)
				(type default)
			)
			(layer "B.SilkS")
		)
		(fp_line
			(start -0.7874 -0.4064)
			(end -0.7874 0.4064)
			(stroke
				(width 0.1524)
				(type default)
			)
			(layer "B.SilkS")
		)
		(fp_line
			(start 0.7874 0.4064)
			(end 0.7874 -0.4064)
			(stroke
				(width 0.1524)
				(type default)
			)
			(layer "B.SilkS")
		)
		(fp_line
			(start -0.7874 0.4064)
			(end 0.7874 0.4064)
			(stroke
				(width 0.1524)
				(type default)
			)
			(layer "B.SilkS")
		)
		(fp_line
			(start 0.67945 -0.305054)
			(end 0.12065 -0.305054)
			(stroke
				(width 0.1)
				(type default)
			)
			(layer "B.Fab")
		)
		(fp_line
			(start 0.12065 -0.305054)
			(end 0.12065 -0.2794)
			(stroke
				(width 0.1)
				(type default)
			)
			(layer "B.Fab")
		)
		(fp_line
			(start -0.12065 -0.3048)
			(end -0.67945 -0.3048)
			(stroke
				(width 0.1)
				(type default)
			)
			(layer "B.Fab")
		)
		(fp_line
			(start -0.67945 -0.3048)
			(end -0.67945 0.3048)
			(stroke
				(width 0.1)
				(type default)
			)
			(layer "B.Fab")
		)
		(fp_line
			(start 0.12065 -0.2794)
			(end -0.12065 -0.2794)
			(stroke
				(width 0.1)
				(type default)
			)
			(layer "B.Fab")
		)
		(fp_line
			(start -0.12065 -0.2794)
			(end -0.12065 -0.3048)
			(stroke
				(width 0.1)
				(type default)
			)
			(layer "B.Fab")
		)
		(fp_line
			(start 0.12065 0.2794)
			(end 0.12065 0.3048)
			(stroke
				(width 0.1)
				(type default)
			)
			(layer "B.Fab")
		)
		(fp_line
			(start -0.120396 0.2794)
			(end 0.12065 0.2794)
			(stroke
				(width 0.1)
				(type default)
			)
			(layer "B.Fab")
		)
		(fp_line
			(start 0.67945 0.3048)
			(end 0.67945 -0.305054)
			(stroke
				(width 0.1)
				(type default)
			)
			(layer "B.Fab")
		)
		(fp_line
			(start 0.12065 0.3048)
			(end 0.67945 0.3048)
			(stroke
				(width 0.1)
				(type default)
			)
			(layer "B.Fab")
		)
		(fp_line
			(start -0.120396 0.3048)
			(end -0.120396 0.2794)
			(stroke
				(width 0.1)
				(type default)
			)
			(layer "B.Fab")
		)
		(fp_line
			(start -0.67945 0.3048)
			(end -0.120396 0.3048)
			(stroke
				(width 0.1)
				(type default)
			)
			(layer "B.Fab")
		)
		(pad "1" smd circle
			(at 0.40005 0 270)
			(size 0 0)
			(layers "B.Cu" "B.Mask" "B.Paste")
			(net "PVDDCR_CPU0_P0_VCC")
		)
		(pad "2" smd circle
			(at -0.40005 0 270)
			(size 0 0)
			(layers "B.Cu" "B.Mask" "B.Paste")
			(net "GND")
		)
	)
	(footprint ""
		(layer "B.Cu")
		(at 171.196 -116.296948)
		(property "Reference" "R889"
			(at 0 0 0)
			(layer "B.SilkS")
			(hide yes)
			(effects
				(font
					(size 1.27 1.27)
				)
				(justify mirror)
			)
		)
		(property "Value" ""
			(at 0 0 0)
			(layer "B.Fab")
			(effects
				(font
					(size 1.27 1.27)
				)
				(justify mirror)
			)
		)
		(duplicate_pad_numbers_are_jumpers no)
		(fp_line
			(start -0.7874 -0.4064)
			(end -0.7874 0.4064)
			(stroke
				(width 0.1524)
				(type default)
			)
			(layer "B.SilkS")
		)
		(fp_line
			(start -0.7874 0.4064)
			(end 0.7874 0.4064)
			(stroke
				(width 0.1524)
				(type default)
			)
			(layer "B.SilkS")
		)
		(fp_line
			(start 0.7874 -0.4064)
			(end -0.7874 -0.4064)
			(stroke
				(width 0.1524)
				(type default)
			)
			(layer "B.SilkS")
		)
		(fp_line
			(start 0.7874 0.4064)
			(end 0.7874 -0.4064)
			(stroke
				(width 0.1524)
				(type default)
			)
			(layer "B.SilkS")
		)
		(fp_line
			(start -0.67945 -0.3048)
			(end -0.67945 0.3048)
			(stroke
				(width 0.1)
				(type default)
			)
			(layer "B.Fab")
		)
		(fp_line
			(start -0.67945 0.3048)
			(end -0.120396 0.3048)
			(stroke
				(width 0.1)
				(type default)
			)
			(layer "B.Fab")
		)
		(fp_line
			(start -0.12065 -0.3048)
			(end -0.67945 -0.3048)
			(stroke
				(width 0.1)
				(type default)
			)
			(layer "B.Fab")
		)
		(fp_line
			(start -0.12065 -0.2794)
			(end -0.12065 -0.3048)
			(stroke
				(width 0.1)
				(type default)
			)
			(layer "B.Fab")
		)
		(fp_line
			(start -0.120396 0.2794)
			(end 0.12065 0.2794)
			(stroke
				(width 0.1)
				(type default)
			)
			(layer "B.Fab")
		)
		(fp_line
			(start -0.120396 0.3048)
			(end -0.120396 0.2794)
			(stroke
				(width 0.1)
				(type default)
			)
			(layer "B.Fab")
		)
		(fp_line
			(start 0.12065 -0.305054)
			(end 0.12065 -0.2794)
			(stroke
				(width 0.1)
				(type default)
			)
			(layer "B.Fab")
		)
		(fp_line
			(start 0.12065 -0.2794)
			(end -0.12065 -0.2794)
			(stroke
				(width 0.1)
				(type default)
			)
			(layer "B.Fab")
		)
		(fp_line
			(start 0.12065 0.2794)
			(end 0.12065 0.3048)
			(stroke
				(width 0.1)
				(type default)
			)
			(layer "B.Fab")
		)
		(fp_line
			(start 0.12065 0.3048)
			(end 0.67945 0.3048)
			(stroke
				(width 0.1)
				(type default)
			)
			(layer "B.Fab")
		)
		(fp_line
			(start 0.67945 -0.305054)
			(end 0.12065 -0.305054)
			(stroke
				(width 0.1)
				(type default)
			)
			(layer "B.Fab")
		)
		(fp_line
			(start 0.67945 0.3048)
			(end 0.67945 -0.305054)
			(stroke
				(width 0.1)
				(type default)
			)
			(layer "B.Fab")
		)
		(pad "1" smd circle
			(at 0.40005 0 180)
			(size 0 0)
			(layers "B.Cu" "B.Mask" "B.Paste")
			(net "SCM_SPARE_0")
		)
		(pad "2" smd circle
			(at -0.40005 0 180)
			(size 0 0)
			(layers "B.Cu" "B.Mask" "B.Paste")
			(net "GND")
		)
	)
)
